(kicad_pcb
	(version 20260206)
	(generator "pcbnew")
	(generator_version "10.0")
	(general
		(thickness 1.6)
		(legacy_teardrops no)
	)
	(paper "A4")
	(title_block
		(title "01162023_DA0F0TEBIF0_F0T_Expander_BD_F_brd_V02_OCP.brd")
		(comment 1 "Grand Teton / footprints 3400-3405 of 9728")
	)
	(layers
		(0 "F.Cu" signal "TOP")
		(4 "In1.Cu" signal "GND")
		(6 "In2.Cu" signal "VCC")
		(8 "In3.Cu" signal "VCC1")
		(10 "In4.Cu" signal "GND1")
		(12 "In5.Cu" signal "IN1")
		(14 "In6.Cu" signal "GND2")
		(16 "In7.Cu" signal "IN2")
		(18 "In8.Cu" signal "GND3")
		(20 "In9.Cu" signal "IN3")
		(22 "In10.Cu" signal "GND4")
		(24 "In11.Cu" signal "IN4")
		(26 "In12.Cu" signal "GND5")
		(28 "In13.Cu" signal "IN5")
		(30 "In14.Cu" signal "GND6")
		(32 "In15.Cu" signal "IN6")
		(34 "In16.Cu" signal "GND7")
		(2 "B.Cu" signal "BOTTOM")
		(9 "F.Adhes" user "F.Adhesive")
		(11 "B.Adhes" user "B.Adhesive")
		(13 "F.Paste" user "Package Geometry/Pastemask Top")
		(15 "B.Paste" user "Package Geometry/Pastemask Bottom")
		(5 "F.SilkS" user "Ref Des/Silkscreen Top")
		(7 "B.SilkS" user "Ref Des/Silkscreen Bottom")
		(1 "F.Mask" user "Board Geometry/Soldermask Top")
		(3 "B.Mask" user "Board Geometry/Soldermask Bottom")
		(17 "Dwgs.User" user "User.Drawings")
		(19 "Cmts.User" user "User.Comments")
		(21 "Eco1.User" user "User.Eco1")
		(23 "Eco2.User" user "User.Eco2")
		(25 "Edge.Cuts" user "Board Geometry/Outline")
		(27 "Margin" user)
		(31 "F.CrtYd" user "Package Geometry/Place Bound Top")
		(29 "B.CrtYd" user "Package Geometry/Place Bound Bottom")
		(35 "F.Fab" user "Ref Des/Assembly Top")
		(33 "B.Fab" user "Ref Des/Assembly Bottom")
	)
	(footprint ""
		(layer "F.Cu")
		(at 232.613962 -136.361424 -90)
		(property "Reference" "Y7"
			(at 2.250694 0.915162 0)
			(unlocked yes)
			(layer "F.SilkS")
			(effects
				(font
					(size 0.7874 0.5842)
					(thickness 0.1524)
				)
				(justify left)
			)
		)
		(property "Value" ""
			(at 0 0 270)
			(layer "F.Fab")
			(effects
				(font
					(size 1.27 1.27)
				)
			)
		)
		(duplicate_pad_numbers_are_jumpers no)
		(fp_line
			(start -1.538732 1.937004)
			(end -1.538732 -1.937004)
			(stroke
				(width 0.1524)
				(type default)
			)
			(layer "F.SilkS")
		)
		(fp_line
			(start 1.538732 1.937004)
			(end -1.538732 1.937004)
			(stroke
				(width 0.1524)
				(type default)
			)
			(layer "F.SilkS")
		)
		(fp_line
			(start -1.538732 -1.937004)
			(end 1.538732 -1.937004)
			(stroke
				(width 0.1524)
				(type default)
			)
			(layer "F.SilkS")
		)
		(fp_line
			(start 1.538732 -1.937004)
			(end 1.538732 1.937004)
			(stroke
				(width 0.1524)
				(type default)
			)
			(layer "F.SilkS")
		)
		(fp_poly
			(pts
				(xy -2.758694 -2.478532) (xy -2.146046 -3.09118) (xy -1.839722 -2.172208)
			)
			(stroke
				(width 0)
				(type default)
			)
			(fill yes)
			(layer "F.SilkS")
		)
		(fp_line
			(start -1.299972 1.649984)
			(end -1.299972 -1.649984)
			(stroke
				(width 0.1)
				(type default)
			)
			(layer "F.Fab")
		)
		(fp_line
			(start 1.299972 1.649984)
			(end -1.299972 1.649984)
			(stroke
				(width 0.1)
				(type default)
			)
			(layer "F.Fab")
		)
		(fp_line
			(start -1.299972 -1.649984)
			(end 1.299972 -1.649984)
			(stroke
				(width 0.1)
				(type default)
			)
			(layer "F.Fab")
		)
		(fp_line
			(start 1.299972 -1.649984)
			(end 1.299972 1.649984)
			(stroke
				(width 0.1)
				(type default)
			)
			(layer "F.Fab")
		)
		(fp_poly
			(pts
				(xy -2.5908 -0.626872) (xy -2.5908 -1.493266) (xy -1.724406 -1.059942)
			)
			(stroke
				(width 0)
				(type default)
			)
			(fill yes)
			(layer "F.Fab")
		)
		(pad "1" smd rect
			(at -0.8001 -1.059942 270)
			(size 1.2192 1.4986)
			(layers "F.Cu" "F.Mask" "F.Paste")
			(net "XTAL_CK440_PEX_25M_R_XIN")
		)
		(pad "2" smd rect
			(at -0.8001 1.059942 270)
			(size 1.2192 1.4986)
			(layers "F.Cu" "F.Mask" "F.Paste")
			(net "GND")
		)
		(pad "3" smd rect
			(at 0.8001 1.059942 270)
			(size 1.2192 1.4986)
			(layers "F.Cu" "F.Mask" "F.Paste")
			(net "XTAL_CK440_PEX_25M_XOUT")
		)
		(pad "4" smd rect
			(at 0.8001 -1.059942 270)
			(size 1.2192 1.4986)
			(layers "F.Cu" "F.Mask" "F.Paste")
			(net "GND")
		)
	)
	(footprint ""
		(layer "F.Cu")
		(at 369.071144 -146.205956 180)
		(property "Reference" "C621"
			(at 0 0 180)
			(layer "F.SilkS")
			(hide yes)
			(effects
				(font
					(size 1.27 1.27)
				)
			)
		)
		(property "Value" ""
			(at 0 0 180)
			(layer "F.Fab")
			(effects
				(font
					(size 1.27 1.27)
				)
			)
		)
		(duplicate_pad_numbers_are_jumpers no)
		(fp_line
			(start 0.7874 0.4064)
			(end -0.7874 0.4064)
			(stroke
				(width 0.1524)
				(type default)
			)
			(layer "F.SilkS")
		)
		(fp_line
			(start 0.7874 -0.4064)
			(end 0.7874 0.4064)
			(stroke
				(width 0.1524)
				(type default)
			)
			(layer "F.SilkS")
		)
		(fp_line
			(start -0.7874 0.4064)
			(end -0.7874 -0.4064)
			(stroke
				(width 0.1524)
				(type default)
			)
			(layer "F.SilkS")
		)
		(fp_line
			(start -0.7874 -0.4064)
			(end 0.7874 -0.4064)
			(stroke
				(width 0.1524)
				(type default)
			)
			(layer "F.SilkS")
		)
		(fp_line
			(start 0.67945 0.3048)
			(end 0.120396 0.3048)
			(stroke
				(width 0.1)
				(type default)
			)
			(layer "F.Fab")
		)
		(fp_line
			(start 0.67945 -0.3048)
			(end 0.67945 0.3048)
			(stroke
				(width 0.1)
				(type default)
			)
			(layer "F.Fab")
		)
		(fp_line
			(start 0.12065 -0.2794)
			(end 0.12065 -0.3048)
			(stroke
				(width 0.1)
				(type default)
			)
			(layer "F.Fab")
		)
		(fp_line
			(start 0.12065 -0.3048)
			(end 0.67945 -0.3048)
			(stroke
				(width 0.1)
				(type default)
			)
			(layer "F.Fab")
		)
		(fp_line
			(start 0.120396 0.3048)
			(end 0.120396 0.2794)
			(stroke
				(width 0.1)
				(type default)
			)
			(layer "F.Fab")
		)
		(fp_line
			(start 0.120396 0.2794)
			(end -0.12065 0.2794)
			(stroke
				(width 0.1)
				(type default)
			)
			(layer "F.Fab")
		)
		(fp_line
			(start -0.12065 0.3048)
			(end -0.67945 0.3048)
			(stroke
				(width 0.1)
				(type default)
			)
			(layer "F.Fab")
		)
		(fp_line
			(start -0.12065 0.2794)
			(end -0.12065 0.3048)
			(stroke
				(width 0.1)
				(type default)
			)
			(layer "F.Fab")
		)
		(fp_line
			(start -0.12065 -0.2794)
			(end 0.12065 -0.2794)
			(stroke
				(width 0.1)
				(type default)
			)
			(layer "F.Fab")
		)
		(fp_line
			(start -0.12065 -0.305054)
			(end -0.12065 -0.2794)
			(stroke
				(width 0.1)
				(type default)
			)
			(layer "F.Fab")
		)
		(fp_line
			(start -0.67945 0.3048)
			(end -0.67945 -0.305054)
			(stroke
				(width 0.1)
				(type default)
			)
			(layer "F.Fab")
		)
		(fp_line
			(start -0.67945 -0.305054)
			(end -0.12065 -0.305054)
			(stroke
				(width 0.1)
				(type default)
			)
			(layer "F.Fab")
		)
		(pad "1" smd circle
			(at -0.40005 0 180)
			(size 0 0)
			(layers "F.Cu" "F.Mask" "F.Paste")
			(net "P12V_NIC6_VIN_P")
		)
		(pad "2" smd circle
			(at 0.40005 0 180)
			(size 0 0)
			(layers "F.Cu" "F.Mask" "F.Paste")
			(net "P12V_NIC6_VIN_N")
		)
	)
	(footprint ""
		(layer "F.Cu")
		(at 338.074 -165.989 180)
		(property "Reference" "R4773"
			(at 0 0 180)
			(layer "F.SilkS")
			(hide yes)
			(effects
				(font
					(size 1.27 1.27)
				)
			)
		)
		(property "Value" ""
			(at 0 0 180)
			(layer "F.Fab")
			(effects
				(font
					(size 1.27 1.27)
				)
			)
		)
		(duplicate_pad_numbers_are_jumpers no)
		(fp_line
			(start 0.7874 0.4064)
			(end -0.7874 0.4064)
			(stroke
				(width 0.1524)
				(type default)
			)
			(layer "F.SilkS")
		)
		(fp_line
			(start 0.7874 -0.4064)
			(end 0.7874 0.4064)
			(stroke
				(width 0.1524)
				(type default)
			)
			(layer "F.SilkS")
		)
		(fp_line
			(start -0.7874 0.4064)
			(end -0.7874 -0.4064)
			(stroke
				(width 0.1524)
				(type default)
			)
			(layer "F.SilkS")
		)
		(fp_line
			(start -0.7874 -0.4064)
			(end 0.7874 -0.4064)
			(stroke
				(width 0.1524)
				(type default)
			)
			(layer "F.SilkS")
		)
		(fp_line
			(start 0.67945 0.3048)
			(end 0.120396 0.3048)
			(stroke
				(width 0.1)
				(type default)
			)
			(layer "F.Fab")
		)
		(fp_line
			(start 0.67945 -0.3048)
			(end 0.67945 0.3048)
			(stroke
				(width 0.1)
				(type default)
			)
			(layer "F.Fab")
		)
		(fp_line
			(start 0.12065 -0.2794)
			(end 0.12065 -0.3048)
			(stroke
				(width 0.1)
				(type default)
			)
			(layer "F.Fab")
		)
		(fp_line
			(start 0.12065 -0.3048)
			(end 0.67945 -0.3048)
			(stroke
				(width 0.1)
				(type default)
			)
			(layer "F.Fab")
		)
		(fp_line
			(start 0.120396 0.3048)
			(end 0.120396 0.2794)
			(stroke
				(width 0.1)
				(type default)
			)
			(layer "F.Fab")
		)
		(fp_line
			(start 0.120396 0.2794)
			(end -0.12065 0.2794)
			(stroke
				(width 0.1)
				(type default)
			)
			(layer "F.Fab")
		)
		(fp_line
			(start -0.12065 0.3048)
			(end -0.67945 0.3048)
			(stroke
				(width 0.1)
				(type default)
			)
			(layer "F.Fab")
		)
		(fp_line
			(start -0.12065 0.2794)
			(end -0.12065 0.3048)
			(stroke
				(width 0.1)
				(type default)
			)
			(layer "F.Fab")
		)
		(fp_line
			(start -0.12065 -0.2794)
			(end 0.12065 -0.2794)
			(stroke
				(width 0.1)
				(type default)
			)
			(layer "F.Fab")
		)
		(fp_line
			(start -0.12065 -0.305054)
			(end -0.12065 -0.2794)
			(stroke
				(width 0.1)
				(type default)
			)
			(layer "F.Fab")
		)
		(fp_line
			(start -0.67945 0.3048)
			(end -0.67945 -0.305054)
			(stroke
				(width 0.1)
				(type default)
			)
			(layer "F.Fab")
		)
		(fp_line
			(start -0.67945 -0.305054)
			(end -0.12065 -0.305054)
			(stroke
				(width 0.1)
				(type default)
			)
			(layer "F.Fab")
		)
		(pad "1" smd circle
			(at -0.40005 0 180)
			(size 0 0)
			(layers "F.Cu" "F.Mask" "F.Paste")
			(net "SSD11_PEX_PWR_EN")
		)
		(pad "2" smd circle
			(at 0.40005 0 180)
			(size 0 0)
			(layers "F.Cu" "F.Mask" "F.Paste")
			(net "SSD11_PEX_PWR_EN_R")
		)
	)
	(footprint ""
		(layer "F.Cu")
		(at 211.400136 -185.702956 -90)
		(property "Reference" "U352"
			(at -0.072644 -1.910334 90)
			(unlocked yes)
			(layer "F.SilkS")
			(effects
				(font
					(size 0.7874 0.5842)
					(thickness 0.1524)
				)
			)
		)
		(property "Value" ""
			(at 0 0 270)
			(layer "F.Fab")
			(effects
				(font
					(size 1.27 1.27)
				)
			)
		)
		(duplicate_pad_numbers_are_jumpers no)
		(fp_line
			(start -1.7272 1.1176)
			(end -1.7272 -1.1176)
			(stroke
				(width 0.1524)
				(type default)
			)
			(layer "F.SilkS")
		)
		(fp_line
			(start 1.7272 1.1176)
			(end -1.7272 1.1176)
			(stroke
				(width 0.1524)
				(type default)
			)
			(layer "F.SilkS")
		)
		(fp_line
			(start 0 -0.7366)
			(end -0.254 -1.1176)
			(stroke
				(width 0.1524)
				(type default)
			)
			(layer "F.SilkS")
		)
		(fp_line
			(start -0.254 -1.1176)
			(end -1.7272 -1.1176)
			(stroke
				(width 0.1524)
				(type default)
			)
			(layer "F.SilkS")
		)
		(fp_line
			(start 0.254 -1.1176)
			(end 0 -0.7366)
			(stroke
				(width 0.1524)
				(type default)
			)
			(layer "F.SilkS")
		)
		(fp_line
			(start 1.7272 -1.1176)
			(end 1.7272 1.1176)
			(stroke
				(width 0.1524)
				(type default)
			)
			(layer "F.SilkS")
		)
		(fp_line
			(start 1.7272 -1.1176)
			(end 0.254 -1.1176)
			(stroke
				(width 0.1524)
				(type default)
			)
			(layer "F.SilkS")
		)
		(fp_poly
			(pts
				(xy -1.70942 -1.378204) (xy -2.09042 -2.140204) (xy -1.32842 -2.140204)
			)
			(stroke
				(width 0)
				(type default)
			)
			(fill yes)
			(layer "F.SilkS")
		)
		(fp_line
			(start -1.5748 1.1176)
			(end 1.5748 1.1176)
			(stroke
				(width 0.1)
				(type default)
			)
			(layer "F.Fab")
		)
		(fp_line
			(start 1.5748 1.1176)
			(end 1.5748 -1.1176)
			(stroke
				(width 0.1)
				(type default)
			)
			(layer "F.Fab")
		)
		(fp_line
			(start -1.5748 -1.1176)
			(end -1.5748 1.1176)
			(stroke
				(width 0.1)
				(type default)
			)
			(layer "F.Fab")
		)
		(fp_line
			(start 1.5748 -1.1176)
			(end -1.5748 -1.1176)
			(stroke
				(width 0.1)
				(type default)
			)
			(layer "F.Fab")
		)
		(fp_poly
			(pts
				(xy -1.9558 -0.649986) (xy -2.7178 -0.268986) (xy -2.7178 -1.030986)
			)
			(stroke
				(width 0)
				(type default)
			)
			(fill yes)
			(layer "F.Fab")
		)
		(pad "1" smd rect
			(at -0.999998 -0.649986 180)
			(size 0.3556 1.1176)
			(layers "F.Cu" "F.Mask" "F.Paste")
			(net "BIC_SEL_FLASH_SW2_R")
		)
		(pad "2" smd rect
			(at -0.999998 0 180)
			(size 0.3556 1.1176)
			(layers "F.Cu" "F.Mask" "F.Paste")
			(net "GND")
		)
		(pad "3" smd rect
			(at -0.999998 0.649986 180)
			(size 0.3556 1.1176)
			(layers "F.Cu" "F.Mask" "F.Paste")
			(net "BIC_SEL_FLASH_SW3_R")
		)
		(pad "4" smd rect
			(at 0.999998 0.649986 180)
			(size 0.3556 1.1176)
			(layers "F.Cu" "F.Mask" "F.Paste")
			(net "SEL_FLASH_PEX3_BUF")
		)
		(pad "5" smd rect
			(at 0.999998 0 180)
			(size 0.3556 1.1176)
			(layers "F.Cu" "F.Mask" "F.Paste")
			(net "P3V3_AUX")
		)
		(pad "6" smd rect
			(at 0.999998 -0.649986 180)
			(size 0.3556 1.1176)
			(layers "F.Cu" "F.Mask" "F.Paste")
			(net "SEL_FLASH_PEX2_BUF")
		)
	)
	(footprint ""
		(layer "F.Cu")
		(at 361.927394 -391.25779 180)
		(property "Reference" "Q245"
			(at -1.302512 -2.186686 0)
			(unlocked yes)
			(layer "F.SilkS")
			(effects
				(font
					(size 0.7874 0.5842)
					(thickness 0.1524)
				)
			)
		)
		(property "Value" ""
			(at 0 0 180)
			(layer "F.Fab")
			(effects
				(font
					(size 1.27 1.27)
				)
			)
		)
		(duplicate_pad_numbers_are_jumpers no)
		(fp_line
			(start 1.376172 1.199896)
			(end -1.376172 1.199896)
			(stroke
				(width 0.1524)
				(type default)
			)
			(layer "F.SilkS")
		)
		(fp_line
			(start 1.376172 -1.199896)
			(end 1.376172 1.199896)
			(stroke
				(width 0.1524)
				(type default)
			)
			(layer "F.SilkS")
		)
		(fp_line
			(start 0.508 -1.199896)
			(end 1.376172 -1.199896)
			(stroke
				(width 0.1524)
				(type default)
			)
			(layer "F.SilkS")
		)
		(fp_line
			(start 0 -0.762)
			(end 0.508 -1.199896)
			(stroke
				(width 0.1524)
				(type default)
			)
			(layer "F.SilkS")
		)
		(fp_line
			(start -0.508 -1.199896)
			(end 0 -0.762)
			(stroke
				(width 0.1524)
				(type default)
			)
			(layer "F.SilkS")
		)
		(fp_line
			(start -1.376172 1.199896)
			(end -1.376172 -1.199896)
			(stroke
				(width 0.1524)
				(type default)
			)
			(layer "F.SilkS")
		)
		(fp_line
			(start -1.376172 -1.199896)
			(end -0.508 -1.199896)
			(stroke
				(width 0.1524)
				(type default)
			)
			(layer "F.SilkS")
		)
		(fp_poly
			(pts
				(xy -1.4605 -0.7493) (xy -2.2225 -1.1303) (xy -2.2225 -0.3683)
			)
			(stroke
				(width 0)
				(type default)
			)
			(fill yes)
			(layer "F.SilkS")
		)
		(fp_line
			(start 0.674878 1.100074)
			(end -0.674878 1.100074)
			(stroke
				(width 0.1)
				(type default)
			)
			(layer "F.Fab")
		)
		(fp_line
			(start 0.674878 -1.100074)
			(end 0.674878 1.100074)
			(stroke
				(width 0.1)
				(type default)
			)
			(layer "F.Fab")
		)
		(fp_line
			(start -0.674878 1.100074)
			(end -0.674878 -1.100074)
			(stroke
				(width 0.1)
				(type default)
			)
			(layer "F.Fab")
		)
		(fp_line
			(start -0.674878 -1.100074)
			(end 0.674878 -1.100074)
			(stroke
				(width 0.1)
				(type default)
			)
			(layer "F.Fab")
		)
		(fp_poly
			(pts
				(xy -1.4605 -0.7493) (xy -2.2225 -1.1303) (xy -2.2225 -0.3683)
			)
			(stroke
				(width 0)
				(type default)
			)
			(fill yes)
			(layer "F.Fab")
		)
		(pad "1" smd rect
			(at -0.899922 -0.750062 90)
			(size 0.6096 0.6096)
			(layers "F.Cu" "F.Mask" "F.Paste")
			(net "GND")
		)
		(pad "2" smd rect
			(at -0.899922 0 90)
			(size 0.4064 0.6096)
			(layers "F.Cu" "F.Mask" "F.Paste")
			(net "MB_3V3IO_RSVD1")
		)
		(pad "3" smd rect
			(at -0.899922 0.750062 90)
			(size 0.6096 0.6096)
			(layers "F.Cu" "F.Mask" "F.Paste")
			(net "MB_3V3IO_RSVD1_ISO")
		)
		(pad "4" smd rect
			(at 0.899922 0.750062 90)
			(size 0.6096 0.6096)
			(layers "F.Cu" "F.Mask" "F.Paste")
			(net "GND")
		)
		(pad "5" smd rect
			(at 0.899922 0 90)
			(size 0.4064 0.6096)
			(layers "F.Cu" "F.Mask" "F.Paste")
			(net "MB_3V3IO_RSVD1_N")
		)
		(pad "6" smd rect
			(at 0.899922 -0.750062 90)
			(size 0.6096 0.6096)
			(layers "F.Cu" "F.Mask" "F.Paste")
			(net "MB_3V3IO_RSVD1_N")
		)
	)
	(footprint ""
		(layer "F.Cu")
		(at 317.735712 -289.230816 -90)
		(property "Reference" "R6397"
			(at 0 0 270)
			(layer "F.SilkS")
			(hide yes)
			(effects
				(font
					(size 1.27 1.27)
				)
			)
		)
		(property "Value" ""
			(at 0 0 270)
			(layer "F.Fab")
			(effects
				(font
					(size 1.27 1.27)
				)
			)
		)
		(duplicate_pad_numbers_are_jumpers no)
		(fp_line
			(start -0.7874 0.4064)
			(end -0.7874 -0.4064)
			(stroke
				(width 0.1524)
				(type default)
			)
			(layer "F.SilkS")
		)
		(fp_line
			(start 0.7874 0.4064)
			(end -0.7874 0.4064)
			(stroke
				(width 0.1524)
				(type default)
			)
			(layer "F.SilkS")
		)
		(fp_line
			(start -0.7874 -0.4064)
			(end 0.7874 -0.4064)
			(stroke
				(width 0.1524)
				(type default)
			)
			(layer "F.SilkS")
		)
		(fp_line
			(start 0.7874 -0.4064)
			(end 0.7874 0.4064)
			(stroke
				(width 0.1524)
				(type default)
			)
			(layer "F.SilkS")
		)
		(fp_line
			(start -0.67945 0.3048)
			(end -0.67945 -0.305054)
			(stroke
				(width 0.1)
				(type default)
			)
			(layer "F.Fab")
		)
		(fp_line
			(start -0.12065 0.3048)
			(end -0.67945 0.3048)
			(stroke
				(width 0.1)
				(type default)
			)
			(layer "F.Fab")
		)
		(fp_line
			(start 0.120396 0.3048)
			(end 0.120396 0.2794)
			(stroke
				(width 0.1)
				(type default)
			)
			(layer "F.Fab")
		)
		(fp_line
			(start 0.67945 0.3048)
			(end 0.120396 0.3048)
			(stroke
				(width 0.1)
				(type default)
			)
			(layer "F.Fab")
		)
		(fp_line
			(start -0.12065 0.2794)
			(end -0.12065 0.3048)
			(stroke
				(width 0.1)
				(type default)
			)
			(layer "F.Fab")
		)
		(fp_line
			(start 0.120396 0.2794)
			(end -0.12065 0.2794)
			(stroke
				(width 0.1)
				(type default)
			)
			(layer "F.Fab")
		)
		(fp_line
			(start -0.12065 -0.2794)
			(end 0.12065 -0.2794)
			(stroke
				(width 0.1)
				(type default)
			)
			(layer "F.Fab")
		)
		(fp_line
			(start 0.12065 -0.2794)
			(end 0.12065 -0.3048)
			(stroke
				(width 0.1)
				(type default)
			)
			(layer "F.Fab")
		)
		(fp_line
			(start 0.12065 -0.3048)
			(end 0.67945 -0.3048)
			(stroke
				(width 0.1)
				(type default)
			)
			(layer "F.Fab")
		)
		(fp_line
			(start 0.67945 -0.3048)
			(end 0.67945 0.3048)
			(stroke
				(width 0.1)
				(type default)
			)
			(layer "F.Fab")
		)
		(fp_line
			(start -0.67945 -0.305054)
			(end -0.12065 -0.305054)
			(stroke
				(width 0.1)
				(type default)
			)
			(layer "F.Fab")
		)
		(fp_line
			(start -0.12065 -0.305054)
			(end -0.12065 -0.2794)
			(stroke
				(width 0.1)
				(type default)
			)
			(layer "F.Fab")
		)
		(pad "1" smd circle
			(at -0.40005 0 270)
			(size 0 0)
			(layers "F.Cu" "F.Mask" "F.Paste")
			(net "RST_PEX2_S0_PERST_N")
		)
		(pad "2" smd circle
			(at 0.40005 0 270)
			(size 0 0)
			(layers "F.Cu" "F.Mask" "F.Paste")
			(net "RST_PEX2_S0_PERST_R_N")
		)
	)
)
